# ZAIUS-LV_CARD-EVT1-X00-BOM-X01_20160825.xls — POP_GA (bom)
| FOXCONN TECHNOLOGY GROUP |  |  |  |  |  |  |  |  |  |  |  |  |
| BILL OF MATERIAL |  |  |  |  |  |  |  |  |  |  |  |  |
| REV OF  BOM |  | CUSTOMER | DELL |  | CUSTOMER P/N |  | PRODUCT CODE |  | PWA  REV |  | DATE |  |
| Sourcing (Single/Sole/Multi) | Critical Commodity (Y or N) | Component Class (1, 2, other) | Dell PSL (Y or N) | Item Number | Foxconn P/N | Dell P/N | Part Description | Manufacturer  Full Name | Manufacturer  Part Number | Qty | RoHS Status | Location |
